(kicad_pcb
	(version 20260206)
	(generator "pcbnew")
	(generator_version "10.0")
	(general
		(thickness 1.6)
		(legacy_teardrops no)
	)
	(paper "A4")
	(title_block
		(title "04192023_DAF0TMB3IC0_F0TG_MB_C_brd_V02_OCP.brd")
		(comment 1 "Grand Teton / footprint 2783 of 8354 (U26), pads 541-651 of 6102")
	)
	(layers
		(0 "F.Cu" signal "TOP")
		(4 "In1.Cu" signal "GND")
		(6 "In2.Cu" signal "IN1")
		(8 "In3.Cu" signal "GND1")
		(10 "In4.Cu" signal "IN2")
		(12 "In5.Cu" signal "GND2")
		(14 "In6.Cu" signal "IN3")
		(16 "In7.Cu" signal "GND3")
		(18 "In8.Cu" signal "VCC")
		(20 "In9.Cu" signal "VCC1")
		(22 "In10.Cu" signal "GND4")
		(24 "In11.Cu" signal "IN4")
		(26 "In12.Cu" signal "GND5")
		(28 "In13.Cu" signal "IN5")
		(30 "In14.Cu" signal "GND6")
		(32 "In15.Cu" signal "IN6")
		(34 "In16.Cu" signal "GND7")
		(2 "B.Cu" signal "BOTTOM")
		(9 "F.Adhes" user "F.Adhesive")
		(11 "B.Adhes" user "B.Adhesive")
		(13 "F.Paste" user "Package Geometry/Pastemask Top")
		(15 "B.Paste" user "Package Geometry/Pastemask Bottom")
		(5 "F.SilkS" user "Ref Des/Silkscreen Top")
		(7 "B.SilkS" user "Ref Des/Silkscreen Bottom")
		(1 "F.Mask" user "Board Geometry/Soldermask Top")
		(3 "B.Mask" user "Board Geometry/Soldermask Bottom")
		(17 "Dwgs.User" user "User.Drawings")
		(19 "Cmts.User" user "User.Comments")
		(21 "Eco1.User" user "User.Eco1")
		(23 "Eco2.User" user "User.Eco2")
		(25 "Edge.Cuts" user "Board Geometry/Outline")
		(27 "Margin" user)
		(31 "F.CrtYd" user "Package Geometry/Place Bound Top")
		(29 "B.CrtYd" user "Package Geometry/Place Bound Bottom")
		(35 "F.Fab" user "Ref Des/Assembly Top")
		(33 "B.Fab" user "Ref Des/Assembly Bottom")
	)
	(footprint ""
		(layer "F.Cu")
		(at 111.927894 -258.880356 180)
		(property "Reference" "U26"
			(at -45.05579 -61.794136 0)
			(unlocked yes)
			(layer "F.SilkS")
			(effects
				(font
					(size 0.7874 0.5842)
					(thickness 0.1524)
				)
			)
		)
		(property "Value" ""
			(at 0 0 180)
			(layer "F.Fab")
			(effects
				(font
					(size 1.27 1.27)
				)
			)
		)
		(duplicate_pad_numbers_are_jumpers no)
		(pad "AG50" smd circle
			(at 10.9601 -15.750032 180)
			(size 0.450088 0.450088)
			(layers "F.Cu" "F.Mask" "F.Paste")
			(net "GMI_CPU1_G0_CPU0_G2_TX_DN<5>")
		)
		(pad "AG51" smd circle
			(at 11.8999 -15.750032 180)
			(size 0.450088 0.450088)
			(layers "F.Cu" "F.Mask" "F.Paste")
			(net "GND")
		)
		(pad "AG52" smd circle
			(at 12.839954 -15.750032 180)
			(size 0.450088 0.450088)
			(layers "F.Cu" "F.Mask" "F.Paste")
			(net "GMI_CPU1_G0_CPU0_G2_TX_DP<2>")
		)
		(pad "AG53" smd circle
			(at 13.780008 -15.750032 180)
			(size 0.450088 0.450088)
			(layers "F.Cu" "F.Mask" "F.Paste")
			(net "GMI_CPU1_G0_CPU0_G2_TX_DN<2>")
		)
		(pad "AG54" smd circle
			(at 14.720062 -15.750032 180)
			(size 0.450088 0.450088)
			(layers "F.Cu" "F.Mask" "F.Paste")
			(net "GND")
		)
		(pad "AG55" smd circle
			(at 15.660116 -15.750032 180)
			(size 0.450088 0.450088)
			(layers "F.Cu" "F.Mask" "F.Paste")
			(net "M_C_CPU1_SA_DQS_DP<8>")
		)
		(pad "AG56" smd circle
			(at 16.599916 -15.750032 180)
			(size 0.450088 0.450088)
			(layers "F.Cu" "F.Mask" "F.Paste")
			(net "GND")
		)
		(pad "AG57" smd circle
			(at 17.53997 -15.750032 180)
			(size 0.450088 0.450088)
			(layers "F.Cu" "F.Mask" "F.Paste")
			(net "M_C_CPU1_SA_DQ<28>")
		)
		(pad "AG58" smd circle
			(at 18.480024 -15.750032 180)
			(size 0.450088 0.450088)
			(layers "F.Cu" "F.Mask" "F.Paste")
			(net "GND")
		)
		(pad "AG59" smd circle
			(at 19.420078 -15.750032 180)
			(size 0.450088 0.450088)
			(layers "F.Cu" "F.Mask" "F.Paste")
			(net "M_D_CPU1_SA_DQS_DP<8>")
		)
		(pad "AG60" smd circle
			(at 20.359878 -15.750032 180)
			(size 0.450088 0.450088)
			(layers "F.Cu" "F.Mask" "F.Paste")
			(net "M_D_CPU1_SA_DQ<28>")
		)
		(pad "AG61" smd circle
			(at 21.299932 -15.750032 180)
			(size 0.450088 0.450088)
			(layers "F.Cu" "F.Mask" "F.Paste")
			(net "GND")
		)
		(pad "AG62" smd circle
			(at 22.239986 -15.750032 180)
			(size 0.450088 0.450088)
			(layers "F.Cu" "F.Mask" "F.Paste")
			(net "M_B_CPU1_SA_DQS_DP<8>")
		)
		(pad "AG63" smd circle
			(at 23.18004 -15.750032 180)
			(size 0.450088 0.450088)
			(layers "F.Cu" "F.Mask" "F.Paste")
			(net "GND")
		)
		(pad "AG64" smd circle
			(at 24.120094 -15.750032 180)
			(size 0.450088 0.450088)
			(layers "F.Cu" "F.Mask" "F.Paste")
			(net "M_B_CPU1_SA_DQ<28>")
		)
		(pad "AG65" smd circle
			(at 25.059894 -15.750032 180)
			(size 0.450088 0.450088)
			(layers "F.Cu" "F.Mask" "F.Paste")
			(net "GND")
		)
		(pad "AG66" smd circle
			(at 25.999948 -15.750032 180)
			(size 0.450088 0.450088)
			(layers "F.Cu" "F.Mask" "F.Paste")
			(net "M_F_CPU1_SA_DQS_DP<8>")
		)
		(pad "AG67" smd circle
			(at 26.940002 -15.750032 180)
			(size 0.450088 0.450088)
			(layers "F.Cu" "F.Mask" "F.Paste")
			(net "M_F_CPU1_SA_DQ<28>")
		)
		(pad "AG68" smd circle
			(at 27.880056 -15.750032 180)
			(size 0.450088 0.450088)
			(layers "F.Cu" "F.Mask" "F.Paste")
			(net "GND")
		)
		(pad "AG69" smd circle
			(at 28.82011 -15.750032 180)
			(size 0.450088 0.450088)
			(layers "F.Cu" "F.Mask" "F.Paste")
			(net "M_E_CPU1_SA_DQS_DP<8>")
		)
		(pad "AG70" smd circle
			(at 29.75991 -15.750032 180)
			(size 0.450088 0.450088)
			(layers "F.Cu" "F.Mask" "F.Paste")
			(net "GND")
		)
		(pad "AG71" smd circle
			(at 30.699964 -15.750032 180)
			(size 0.450088 0.450088)
			(layers "F.Cu" "F.Mask" "F.Paste")
			(net "M_E_CPU1_SA_DQ<28>")
		)
		(pad "AG72" smd circle
			(at 31.640018 -15.750032 180)
			(size 0.450088 0.450088)
			(layers "F.Cu" "F.Mask" "F.Paste")
			(net "GND")
		)
		(pad "AG73" smd circle
			(at 32.580072 -15.750032 180)
			(size 0.450088 0.450088)
			(layers "F.Cu" "F.Mask" "F.Paste")
			(net "M_A_CPU1_SA_DQS_DP<8>")
		)
		(pad "AG74" smd circle
			(at 33.519872 -15.750032 180)
			(size 0.450088 0.450088)
			(layers "F.Cu" "F.Mask" "F.Paste")
			(net "M_A_CPU1_SA_DQ<28>")
		)
		(pad "AG75" smd circle
			(at 34.459926 -15.750032 180)
			(size 0.450088 0.450088)
			(layers "F.Cu" "F.Mask" "F.Paste")
			(net "GND")
		)
		(pad "AH2" smd circle
			(at -33.690052 -14.940026 180)
			(size 0.450088 0.450088)
			(layers "F.Cu" "F.Mask" "F.Paste")
			(net "M_G_CPU1_SA_DQ<30>")
		)
		(pad "AH3" smd circle
			(at -32.749998 -14.940026 180)
			(size 0.450088 0.450088)
			(layers "F.Cu" "F.Mask" "F.Paste")
			(net "GND")
		)
		(pad "AH4" smd circle
			(at -31.809944 -14.940026 180)
			(size 0.450088 0.450088)
			(layers "F.Cu" "F.Mask" "F.Paste")
			(net "M_G_CPU1_SA_DQ<29>")
		)
		(pad "AH5" smd circle
			(at -30.86989 -14.940026 180)
			(size 0.450088 0.450088)
			(layers "F.Cu" "F.Mask" "F.Paste")
			(net "GND")
		)
		(pad "AH6" smd circle
			(at -29.93009 -14.940026 180)
			(size 0.450088 0.450088)
			(layers "F.Cu" "F.Mask" "F.Paste")
			(net "M_K_CPU1_SA_DQ<30>")
		)
		(pad "AH7" smd circle
			(at -28.990036 -14.940026 180)
			(size 0.450088 0.450088)
			(layers "F.Cu" "F.Mask" "F.Paste")
			(net "M_K_CPU1_SA_DQ<29>")
		)
		(pad "AH8" smd circle
			(at -28.049982 -14.940026 180)
			(size 0.450088 0.450088)
			(layers "F.Cu" "F.Mask" "F.Paste")
			(net "GND")
		)
		(pad "AH9" smd circle
			(at -27.109928 -14.940026 180)
			(size 0.450088 0.450088)
			(layers "F.Cu" "F.Mask" "F.Paste")
			(net "M_L_CPU1_SA_DQ<30>")
		)
		(pad "AH10" smd circle
			(at -26.170128 -14.940026 180)
			(size 0.450088 0.450088)
			(layers "F.Cu" "F.Mask" "F.Paste")
			(net "GND")
		)
		(pad "AH11" smd circle
			(at -25.230074 -14.940026 180)
			(size 0.450088 0.450088)
			(layers "F.Cu" "F.Mask" "F.Paste")
			(net "M_L_CPU1_SA_DQ<29>")
		)
		(pad "AH12" smd circle
			(at -24.29002 -14.940026 180)
			(size 0.450088 0.450088)
			(layers "F.Cu" "F.Mask" "F.Paste")
			(net "GND")
		)
		(pad "AH13" smd circle
			(at -23.349966 -14.940026 180)
			(size 0.450088 0.450088)
			(layers "F.Cu" "F.Mask" "F.Paste")
			(net "M_H_CPU1_SA_DQ<30>")
		)
		(pad "AH14" smd circle
			(at -22.409912 -14.940026 180)
			(size 0.450088 0.450088)
			(layers "F.Cu" "F.Mask" "F.Paste")
			(net "M_H_CPU1_SA_DQ<29>")
		)
		(pad "AH15" smd circle
			(at -21.470112 -14.940026 180)
			(size 0.450088 0.450088)
			(layers "F.Cu" "F.Mask" "F.Paste")
			(net "GND")
		)
		(pad "AH16" smd circle
			(at -20.530058 -14.940026 180)
			(size 0.450088 0.450088)
			(layers "F.Cu" "F.Mask" "F.Paste")
			(net "M_J_CPU1_SA_DQ<30>")
		)
		(pad "AH17" smd circle
			(at -19.590004 -14.940026 180)
			(size 0.450088 0.450088)
			(layers "F.Cu" "F.Mask" "F.Paste")
			(net "GND")
		)
		(pad "AH18" smd circle
			(at -18.64995 -14.940026 180)
			(size 0.450088 0.450088)
			(layers "F.Cu" "F.Mask" "F.Paste")
			(net "M_J_CPU1_SA_DQ<29>")
		)
		(pad "AH19" smd circle
			(at -17.709896 -14.940026 180)
			(size 0.450088 0.450088)
			(layers "F.Cu" "F.Mask" "F.Paste")
			(net "GND")
		)
		(pad "AH20" smd circle
			(at -16.770096 -14.940026 180)
			(size 0.450088 0.450088)
			(layers "F.Cu" "F.Mask" "F.Paste")
			(net "M_I_CPU1_SA_DQ<30>")
		)
		(pad "AH21" smd circle
			(at -15.830042 -14.940026 180)
			(size 0.450088 0.450088)
			(layers "F.Cu" "F.Mask" "F.Paste")
			(net "M_I_CPU1_SA_DQ<29>")
		)
		(pad "AH22" smd circle
			(at -14.889988 -14.940026 180)
			(size 0.450088 0.450088)
			(layers "F.Cu" "F.Mask" "F.Paste")
			(net "PVDDCR_SOC_P1")
		)
		(pad "AH23" smd circle
			(at -13.949934 -14.940026 180)
			(size 0.450088 0.450088)
			(layers "F.Cu" "F.Mask" "F.Paste")
			(net "GND")
		)
		(pad "AH24" smd circle
			(at -13.00988 -14.940026 180)
			(size 0.450088 0.450088)
			(layers "F.Cu" "F.Mask" "F.Paste")
			(net "GND")
		)
		(pad "AH25" smd circle
			(at -12.07008 -14.940026 180)
			(size 0.450088 0.450088)
			(layers "F.Cu" "F.Mask" "F.Paste")
			(net "GND")
		)
		(pad "AH26" smd circle
			(at -11.130026 -14.940026 180)
			(size 0.450088 0.450088)
			(layers "F.Cu" "F.Mask" "F.Paste")
			(net "GND")
		)
		(pad "AH27" smd circle
			(at -10.189972 -14.940026 180)
			(size 0.450088 0.450088)
			(layers "F.Cu" "F.Mask" "F.Paste")
			(net "GND")
		)
		(pad "AH28" smd circle
			(at -9.249918 -14.940026 180)
			(size 0.450088 0.450088)
			(layers "F.Cu" "F.Mask" "F.Paste")
			(net "GND")
		)
		(pad "AH29" smd circle
			(at -8.310118 -14.940026 180)
			(size 0.450088 0.450088)
			(layers "F.Cu" "F.Mask" "F.Paste")
			(net "GND")
		)
		(pad "AH30" smd circle
			(at -7.370064 -14.940026 180)
			(size 0.450088 0.450088)
			(layers "F.Cu" "F.Mask" "F.Paste")
			(net "GND")
		)
		(pad "AH31" smd circle
			(at -6.43001 -14.940026 180)
			(size 0.450088 0.450088)
			(layers "F.Cu" "F.Mask" "F.Paste")
			(net "GND")
		)
		(pad "AH32" smd circle
			(at -5.489956 -14.940026 180)
			(size 0.450088 0.450088)
			(layers "F.Cu" "F.Mask" "F.Paste")
			(net "GND")
		)
		(pad "AH33" smd circle
			(at -4.549902 -14.940026 180)
			(size 0.450088 0.450088)
			(layers "F.Cu" "F.Mask" "F.Paste")
			(net "GND")
		)
		(pad "AH34" smd circle
			(at -3.610102 -14.940026 180)
			(size 0.450088 0.450088)
			(layers "F.Cu" "F.Mask" "F.Paste")
			(net "GND")
		)
		(pad "AH35" smd circle
			(at -2.670048 -14.940026 180)
			(size 0.450088 0.450088)
			(layers "F.Cu" "F.Mask" "F.Paste")
			(net "GMI_CPU0_G1_CPU1_G3_TX_DN<2>")
		)
		(pad "AH36" smd circle
			(at -1.729994 -14.940026 180)
			(size 0.450088 0.450088)
			(layers "F.Cu" "F.Mask" "F.Paste")
			(net "GMI_CPU0_G1_CPU1_G3_TX_DP<2>")
		)
		(pad "AH37" smd circle
			(at -0.78994 -14.940026 180)
			(size 0.450088 0.450088)
			(layers "F.Cu" "F.Mask" "F.Paste")
			(net "GND")
		)
		(pad "AH39" smd circle
			(at 1.089914 -14.940026 180)
			(size 0.450088 0.450088)
			(layers "F.Cu" "F.Mask" "F.Paste")
			(net "GND")
		)
		(pad "AH40" smd circle
			(at 2.029968 -14.940026 180)
			(size 0.450088 0.450088)
			(layers "F.Cu" "F.Mask" "F.Paste")
			(net "P5E_CPU1_G1_TX_DP<2>")
		)
		(pad "AH41" smd circle
			(at 2.970022 -14.940026 180)
			(size 0.450088 0.450088)
			(layers "F.Cu" "F.Mask" "F.Paste")
			(net "P5E_CPU1_G1_TX_DN<2>")
		)
		(pad "AH42" smd circle
			(at 3.910076 -14.940026 180)
			(size 0.450088 0.450088)
			(layers "F.Cu" "F.Mask" "F.Paste")
			(net "GND")
		)
		(pad "AH43" smd circle
			(at 4.849876 -14.940026 180)
			(size 0.450088 0.450088)
			(layers "F.Cu" "F.Mask" "F.Paste")
			(net "GND")
		)
		(pad "AH44" smd circle
			(at 5.78993 -14.940026 180)
			(size 0.450088 0.450088)
			(layers "F.Cu" "F.Mask" "F.Paste")
			(net "GND")
		)
		(pad "AH45" smd circle
			(at 6.729984 -14.940026 180)
			(size 0.450088 0.450088)
			(layers "F.Cu" "F.Mask" "F.Paste")
			(net "GND")
		)
		(pad "AH46" smd circle
			(at 7.670038 -14.940026 180)
			(size 0.450088 0.450088)
			(layers "F.Cu" "F.Mask" "F.Paste")
			(net "GND")
		)
		(pad "AH47" smd circle
			(at 8.610092 -14.940026 180)
			(size 0.450088 0.450088)
			(layers "F.Cu" "F.Mask" "F.Paste")
			(net "GND")
		)
		(pad "AH48" smd circle
			(at 9.549892 -14.940026 180)
			(size 0.450088 0.450088)
			(layers "F.Cu" "F.Mask" "F.Paste")
			(net "GND")
		)
		(pad "AH49" smd circle
			(at 10.489946 -14.940026 180)
			(size 0.450088 0.450088)
			(layers "F.Cu" "F.Mask" "F.Paste")
			(net "GND")
		)
		(pad "AH50" smd circle
			(at 11.43 -14.940026 180)
			(size 0.450088 0.450088)
			(layers "F.Cu" "F.Mask" "F.Paste")
			(net "GND")
		)
		(pad "AH51" smd circle
			(at 12.370054 -14.940026 180)
			(size 0.450088 0.450088)
			(layers "F.Cu" "F.Mask" "F.Paste")
			(net "GND")
		)
		(pad "AH52" smd circle
			(at 13.310108 -14.940026 180)
			(size 0.450088 0.450088)
			(layers "F.Cu" "F.Mask" "F.Paste")
			(net "GND")
		)
		(pad "AH53" smd circle
			(at 14.249908 -14.940026 180)
			(size 0.450088 0.450088)
			(layers "F.Cu" "F.Mask" "F.Paste")
			(net "GND")
		)
		(pad "AH54" smd circle
			(at 15.189962 -14.940026 180)
			(size 0.450088 0.450088)
			(layers "F.Cu" "F.Mask" "F.Paste")
			(net "PVDDIO_P1")
		)
		(pad "AH55" smd circle
			(at 16.130016 -14.940026 180)
			(size 0.450088 0.450088)
			(layers "F.Cu" "F.Mask" "F.Paste")
			(net "M_C_CPU1_SA_DQ<29>")
		)
		(pad "AH56" smd circle
			(at 17.07007 -14.940026 180)
			(size 0.450088 0.450088)
			(layers "F.Cu" "F.Mask" "F.Paste")
			(net "M_C_CPU1_SA_DQ<30>")
		)
		(pad "AH57" smd circle
			(at 18.010124 -14.940026 180)
			(size 0.450088 0.450088)
			(layers "F.Cu" "F.Mask" "F.Paste")
			(net "GND")
		)
		(pad "AH58" smd circle
			(at 18.949924 -14.940026 180)
			(size 0.450088 0.450088)
			(layers "F.Cu" "F.Mask" "F.Paste")
			(net "M_D_CPU1_SA_DQ<29>")
		)
		(pad "AH59" smd circle
			(at 19.889978 -14.940026 180)
			(size 0.450088 0.450088)
			(layers "F.Cu" "F.Mask" "F.Paste")
			(net "GND")
		)
		(pad "AH60" smd circle
			(at 20.830032 -14.940026 180)
			(size 0.450088 0.450088)
			(layers "F.Cu" "F.Mask" "F.Paste")
			(net "M_D_CPU1_SA_DQ<30>")
		)
		(pad "AH61" smd circle
			(at 21.770086 -14.940026 180)
			(size 0.450088 0.450088)
			(layers "F.Cu" "F.Mask" "F.Paste")
			(net "GND")
		)
		(pad "AH62" smd circle
			(at 22.709886 -14.940026 180)
			(size 0.450088 0.450088)
			(layers "F.Cu" "F.Mask" "F.Paste")
			(net "M_B_CPU1_SA_DQ<29>")
		)
		(pad "AH63" smd circle
			(at 23.64994 -14.940026 180)
			(size 0.450088 0.450088)
			(layers "F.Cu" "F.Mask" "F.Paste")
			(net "M_B_CPU1_SA_DQ<30>")
		)
		(pad "AH64" smd circle
			(at 24.589994 -14.940026 180)
			(size 0.450088 0.450088)
			(layers "F.Cu" "F.Mask" "F.Paste")
			(net "GND")
		)
		(pad "AH65" smd circle
			(at 25.530048 -14.940026 180)
			(size 0.450088 0.450088)
			(layers "F.Cu" "F.Mask" "F.Paste")
			(net "M_F_CPU1_SA_DQ<29>")
		)
		(pad "AH66" smd circle
			(at 26.470102 -14.940026 180)
			(size 0.450088 0.450088)
			(layers "F.Cu" "F.Mask" "F.Paste")
			(net "GND")
		)
		(pad "AH67" smd circle
			(at 27.409902 -14.940026 180)
			(size 0.450088 0.450088)
			(layers "F.Cu" "F.Mask" "F.Paste")
			(net "M_F_CPU1_SA_DQ<30>")
		)
		(pad "AH68" smd circle
			(at 28.349956 -14.940026 180)
			(size 0.450088 0.450088)
			(layers "F.Cu" "F.Mask" "F.Paste")
			(net "GND")
		)
		(pad "AH69" smd circle
			(at 29.29001 -14.940026 180)
			(size 0.450088 0.450088)
			(layers "F.Cu" "F.Mask" "F.Paste")
			(net "M_E_CPU1_SA_DQ<29>")
		)
		(pad "AH70" smd circle
			(at 30.230064 -14.940026 180)
			(size 0.450088 0.450088)
			(layers "F.Cu" "F.Mask" "F.Paste")
			(net "M_E_CPU1_SA_DQ<30>")
		)
		(pad "AH71" smd circle
			(at 31.170118 -14.940026 180)
			(size 0.450088 0.450088)
			(layers "F.Cu" "F.Mask" "F.Paste")
			(net "GND")
		)
		(pad "AH72" smd circle
			(at 32.109918 -14.940026 180)
			(size 0.450088 0.450088)
			(layers "F.Cu" "F.Mask" "F.Paste")
			(net "M_A_CPU1_SA_DQ<29>")
		)
		(pad "AH73" smd circle
			(at 33.049972 -14.940026 180)
			(size 0.450088 0.450088)
			(layers "F.Cu" "F.Mask" "F.Paste")
			(net "GND")
		)
		(pad "AH74" smd circle
			(at 33.990026 -14.940026 180)
			(size 0.450088 0.450088)
			(layers "F.Cu" "F.Mask" "F.Paste")
			(net "M_A_CPU1_SA_DQ<30>")
		)
		(pad "AJ1" smd circle
			(at -34.159952 -14.13002 180)
			(size 0.450088 0.450088)
			(layers "F.Cu" "F.Mask" "F.Paste")
			(net "GND")
		)
		(pad "AJ2" smd circle
			(at -33.219898 -14.13002 180)
			(size 0.450088 0.450088)
			(layers "F.Cu" "F.Mask" "F.Paste")
			(net "M_G_CPU1_SA_CB<0>")
		)
		(pad "AJ3" smd circle
			(at -32.280098 -14.13002 180)
			(size 0.450088 0.450088)
			(layers "F.Cu" "F.Mask" "F.Paste")
			(net "M_G_CPU1_SA_DQ<31>")
		)
		(pad "AJ4" smd circle
			(at -31.340044 -14.13002 180)
			(size 0.450088 0.450088)
			(layers "F.Cu" "F.Mask" "F.Paste")
			(net "PVDDCR_SOC_P1")
		)
		(pad "AJ5" smd circle
			(at -30.39999 -14.13002 180)
			(size 0.450088 0.450088)
			(layers "F.Cu" "F.Mask" "F.Paste")
			(net "M_K_CPU1_SA_CB<0>")
		)
		(pad "AJ6" smd circle
			(at -29.459936 -14.13002 180)
			(size 0.450088 0.450088)
			(layers "F.Cu" "F.Mask" "F.Paste")
			(net "GND")
		)
		(pad "AJ7" smd circle
			(at -28.519882 -14.13002 180)
			(size 0.450088 0.450088)
			(layers "F.Cu" "F.Mask" "F.Paste")
			(net "M_K_CPU1_SA_DQ<31>")
		)
		(pad "AJ8" smd circle
			(at -27.580082 -14.13002 180)
			(size 0.450088 0.450088)
			(layers "F.Cu" "F.Mask" "F.Paste")
			(net "GND")
		)
		(pad "AJ9" smd circle
			(at -26.640028 -14.13002 180)
			(size 0.450088 0.450088)
			(layers "F.Cu" "F.Mask" "F.Paste")
			(net "M_L_CPU1_SA_CB<0>")
		)
		(pad "AJ10" smd circle
			(at -25.699974 -14.13002 180)
			(size 0.450088 0.450088)
			(layers "F.Cu" "F.Mask" "F.Paste")
			(net "M_L_CPU1_SA_DQ<31>")
		)
		(pad "AJ11" smd circle
			(at -24.75992 -14.13002 180)
			(size 0.450088 0.450088)
			(layers "F.Cu" "F.Mask" "F.Paste")
			(net "PVDDCR_SOC_P1")
		)
		(pad "AJ12" smd circle
			(at -23.82012 -14.13002 180)
			(size 0.450088 0.450088)
			(layers "F.Cu" "F.Mask" "F.Paste")
			(net "M_H_CPU1_SA_CB<0>")
		)
		(pad "AJ13" smd circle
			(at -22.880066 -14.13002 180)
			(size 0.450088 0.450088)
			(layers "F.Cu" "F.Mask" "F.Paste")
			(net "GND")
		)
	)
)
